(kicad_pcb
	(version 20260206)
	(generator "pcbnew")
	(generator_version "10.0")
	(general
		(thickness 1.6)
		(legacy_teardrops no)
	)
	(paper "A4")
	(title_block
		(title "Bryce Canyon_IOM_IOC_16318-2_OCP.brd")
		(comment 1 "Bryce Canyon / footprints 593-600 of 1605")
	)
	(layers
		(0 "F.Cu" signal "TOP")
		(4 "In1.Cu" signal "L2GND")
		(6 "In2.Cu" signal "L3")
		(8 "In3.Cu" signal "L4VCC")
		(10 "In4.Cu" signal "L5VCC")
		(12 "In5.Cu" signal "L6")
		(14 "In6.Cu" signal "L7GND")
		(2 "B.Cu" signal "BOTTOM")
		(9 "F.Adhes" user "F.Adhesive")
		(11 "B.Adhes" user "B.Adhesive")
		(13 "F.Paste" user "Package Geometry/Pastemask Top")
		(15 "B.Paste" user "Package Geometry/Pastemask Bottom")
		(5 "F.SilkS" user "Ref Des/Silkscreen Top")
		(7 "B.SilkS" user "Ref Des/Silkscreen Bottom")
		(1 "F.Mask" user "Board Geometry/Soldermask Top")
		(3 "B.Mask" user "Board Geometry/Soldermask Bottom")
		(17 "Dwgs.User" user "User.Drawings")
		(19 "Cmts.User" user "User.Comments")
		(21 "Eco1.User" user "User.Eco1")
		(23 "Eco2.User" user "User.Eco2")
		(25 "Edge.Cuts" user "Board Geometry/Outline")
		(27 "Margin" user)
		(31 "F.CrtYd" user "Package Geometry/Place Bound Top")
		(29 "B.CrtYd" user "Package Geometry/Place Bound Bottom")
		(35 "F.Fab" user "Ref Des/Assembly Top")
		(33 "B.Fab" user "Ref Des/Assembly Bottom")
	)
	(footprint ""
		(layer "F.Cu")
		(at 19.3294 -175.768)
		(property "Reference" "R533"
			(at 0 0 0)
			(layer "F.SilkS")
			(hide yes)
			(effects
				(font
					(size 1.27 1.27)
				)
			)
		)
		(property "Value" "0R2J-2-GP"
			(at 0.064008 -3.993896 0)
			(unlocked yes)
			(layer "F.Fab")
			(hide yes)
			(effects
				(font
					(size 1.016 1.016)
					(thickness 0.1524)
				)
			)
		)
		(property "Device Type" "R402H16"
			(at 0.064008 -5.517896 0)
			(unlocked yes)
			(layer "F.Fab")
			(hide yes)
			(effects
				(font
					(size 1.016 1.016)
					(thickness 0.1524)
				)
			)
		)
		(duplicate_pad_numbers_are_jumpers no)
		(fp_line
			(start -0.508 -0.9398)
			(end -0.508 0.9398)
			(stroke
				(width 0.1524)
				(type default)
			)
			(layer "F.SilkS")
		)
		(fp_line
			(start 0.508 -0.9398)
			(end -0.508 -0.9398)
			(stroke
				(width 0.1524)
				(type default)
			)
			(layer "F.SilkS")
		)
		(fp_rect
			(start -0.508 0.9398)
			(end 0.508 -0.9398)
			(stroke
				(width 0)
				(type default)
			)
			(fill no)
			(layer "F.CrtYd")
		)
		(fp_rect
			(start -0.508 0.9398)
			(end 0.508 -0.9398)
			(stroke
				(width 0)
				(type default)
			)
			(fill no)
			(layer "F.Fab")
		)
		(pad "1" smd custom
			(at 0 -0.4445)
			(size 0.1397 0.1397)
			(layers "F.Cu" "F.Mask" "F.Paste")
			(net "P5V_STBY")
			(options
				(clearance outline)
				(anchor circle)
			)
			(primitives
				(gr_poly
					(pts
						(arc
							(start -0.1778 -0.2794)
							(mid -0.249642 -0.249642)
							(end -0.2794 -0.1778)
						)
						(arc
							(start -0.2794 0.1778)
							(mid -0.249642 0.249642)
							(end -0.1778 0.2794)
						)
						(arc
							(start 0.1778 0.2794)
							(mid 0.249642 0.249642)
							(end 0.2794 0.1778)
						)
						(arc
							(start 0.2794 -0.1778)
							(mid 0.249642 -0.249642)
							(end 0.1778 -0.2794)
						)
					)
					(width 0)
					(fill yes)
				)
			)
		)
		(pad "2" smd custom
			(at 0 0.4445)
			(size 0.1397 0.1397)
			(layers "F.Cu" "F.Mask" "F.Paste")
			(net "TPS74801_P1V2_STBY_BIAS")
			(options
				(clearance outline)
				(anchor circle)
			)
			(primitives
				(gr_poly
					(pts
						(arc
							(start -0.1778 -0.2794)
							(mid -0.249642 -0.249642)
							(end -0.2794 -0.1778)
						)
						(arc
							(start -0.2794 0.1778)
							(mid -0.249642 0.249642)
							(end -0.1778 0.2794)
						)
						(arc
							(start 0.1778 0.2794)
							(mid 0.249642 0.249642)
							(end 0.2794 0.1778)
						)
						(arc
							(start 0.2794 -0.1778)
							(mid 0.249642 -0.249642)
							(end 0.1778 -0.2794)
						)
					)
					(width 0)
					(fill yes)
				)
			)
		)
	)
	(footprint ""
		(layer "F.Cu")
		(at 180.7718 -88.138 180)
		(property "Reference" "R654"
			(at 0 0 180)
			(layer "F.SilkS")
			(hide yes)
			(effects
				(font
					(size 1.27 1.27)
				)
			)
		)
		(property "Value" "10KR2F-2-GP"
			(at 0.064008 -3.993896 180)
			(unlocked yes)
			(layer "F.Fab")
			(hide yes)
			(effects
				(font
					(size 1.016 1.016)
					(thickness 0.1524)
				)
			)
		)
		(property "Device Type" "R402H16"
			(at 0.064008 -5.517896 180)
			(unlocked yes)
			(layer "F.Fab")
			(hide yes)
			(effects
				(font
					(size 1.016 1.016)
					(thickness 0.1524)
				)
			)
		)
		(duplicate_pad_numbers_are_jumpers no)
		(fp_line
			(start 0.508 -0.9398)
			(end -0.508 -0.9398)
			(stroke
				(width 0.1524)
				(type default)
			)
			(layer "F.SilkS")
		)
		(fp_line
			(start -0.508 -0.9398)
			(end -0.508 0.9398)
			(stroke
				(width 0.1524)
				(type default)
			)
			(layer "F.SilkS")
		)
		(fp_rect
			(start -0.508 0.9398)
			(end 0.508 -0.9398)
			(stroke
				(width 0)
				(type default)
			)
			(fill no)
			(layer "F.CrtYd")
		)
		(fp_rect
			(start -0.508 0.9398)
			(end 0.508 -0.9398)
			(stroke
				(width 0)
				(type default)
			)
			(fill no)
			(layer "F.Fab")
		)
		(pad "1" smd custom
			(at 0 -0.4445 180)
			(size 0.1397 0.1397)
			(layers "F.Cu" "F.Mask" "F.Paste")
			(net "SYS_DBMODE2")
			(options
				(clearance outline)
				(anchor circle)
			)
			(primitives
				(gr_poly
					(pts
						(arc
							(start -0.1778 -0.2794)
							(mid -0.249642 -0.249642)
							(end -0.2794 -0.1778)
						)
						(arc
							(start -0.2794 0.1778)
							(mid -0.249642 0.249642)
							(end -0.1778 0.2794)
						)
						(arc
							(start 0.1778 0.2794)
							(mid 0.249642 0.249642)
							(end 0.2794 0.1778)
						)
						(arc
							(start 0.2794 -0.1778)
							(mid 0.249642 -0.249642)
							(end 0.1778 -0.2794)
						)
					)
					(width 0)
					(fill yes)
				)
			)
		)
		(pad "2" smd custom
			(at 0 0.4445 180)
			(size 0.1397 0.1397)
			(layers "F.Cu" "F.Mask" "F.Paste")
			(net "GND")
			(options
				(clearance outline)
				(anchor circle)
			)
			(primitives
				(gr_poly
					(pts
						(arc
							(start -0.1778 -0.2794)
							(mid -0.249642 -0.249642)
							(end -0.2794 -0.1778)
						)
						(arc
							(start -0.2794 0.1778)
							(mid -0.249642 0.249642)
							(end -0.1778 0.2794)
						)
						(arc
							(start 0.1778 0.2794)
							(mid 0.249642 0.249642)
							(end 0.2794 0.1778)
						)
						(arc
							(start 0.2794 -0.1778)
							(mid 0.249642 -0.249642)
							(end 0.1778 -0.2794)
						)
					)
					(width 0)
					(fill yes)
				)
			)
		)
	)
	(footprint ""
		(layer "F.Cu")
		(at 98.3996 -170.6372 -90)
		(property "Reference" "R724"
			(at 0 0 270)
			(layer "F.SilkS")
			(hide yes)
			(effects
				(font
					(size 1.27 1.27)
				)
			)
		)
		(property "Value" "0R2J-2-GP"
			(at 0.064008 -3.993896 270)
			(unlocked yes)
			(layer "F.Fab")
			(hide yes)
			(effects
				(font
					(size 1.016 1.016)
					(thickness 0.1524)
				)
			)
		)
		(property "Device Type" "R402H16"
			(at 0.064008 -5.517896 270)
			(unlocked yes)
			(layer "F.Fab")
			(hide yes)
			(effects
				(font
					(size 1.016 1.016)
					(thickness 0.1524)
				)
			)
		)
		(duplicate_pad_numbers_are_jumpers no)
		(fp_line
			(start -0.508 -0.9398)
			(end -0.508 0.9398)
			(stroke
				(width 0.1524)
				(type default)
			)
			(layer "F.SilkS")
		)
		(fp_line
			(start 0.508 -0.9398)
			(end -0.508 -0.9398)
			(stroke
				(width 0.1524)
				(type default)
			)
			(layer "F.SilkS")
		)
		(fp_rect
			(start -0.508 0.9398)
			(end 0.508 -0.9398)
			(stroke
				(width 0)
				(type default)
			)
			(fill no)
			(layer "F.CrtYd")
		)
		(fp_rect
			(start -0.508 0.9398)
			(end 0.508 -0.9398)
			(stroke
				(width 0)
				(type default)
			)
			(fill no)
			(layer "F.Fab")
		)
		(pad "1" smd custom
			(at 0 -0.4445 270)
			(size 0.1397 0.1397)
			(layers "F.Cu" "F.Mask" "F.Paste")
			(net "DPB_MISC_ALERT_OUT")
			(options
				(clearance outline)
				(anchor circle)
			)
			(primitives
				(gr_poly
					(pts
						(arc
							(start -0.1778 -0.2794)
							(mid -0.249642 -0.249642)
							(end -0.2794 -0.1778)
						)
						(arc
							(start -0.2794 0.1778)
							(mid -0.249642 0.249642)
							(end -0.1778 0.2794)
						)
						(arc
							(start 0.1778 0.2794)
							(mid 0.249642 0.249642)
							(end 0.2794 0.1778)
						)
						(arc
							(start 0.2794 -0.1778)
							(mid 0.249642 -0.249642)
							(end 0.1778 -0.2794)
						)
					)
					(width 0)
					(fill yes)
				)
			)
		)
		(pad "2" smd custom
			(at 0 0.4445 270)
			(size 0.1397 0.1397)
			(layers "F.Cu" "F.Mask" "F.Paste")
			(net "DPB_MISC_ALERT_OUT_R")
			(options
				(clearance outline)
				(anchor circle)
			)
			(primitives
				(gr_poly
					(pts
						(arc
							(start -0.1778 -0.2794)
							(mid -0.249642 -0.249642)
							(end -0.2794 -0.1778)
						)
						(arc
							(start -0.2794 0.1778)
							(mid -0.249642 0.249642)
							(end -0.1778 0.2794)
						)
						(arc
							(start 0.1778 0.2794)
							(mid 0.249642 0.249642)
							(end 0.2794 0.1778)
						)
						(arc
							(start 0.2794 -0.1778)
							(mid 0.249642 -0.249642)
							(end 0.1778 -0.2794)
						)
					)
					(width 0)
					(fill yes)
				)
			)
		)
	)
	(footprint ""
		(layer "F.Cu")
		(at 155.499816 -109.99978)
		(property "Reference" ""
			(at 0 0 0)
			(layer "F.SilkS")
			(hide yes)
			(effects
				(font
					(size 1.27 1.27)
				)
			)
		)
		(property "Value" "*"
			(at -6.38175 0.19685 0)
			(unlocked yes)
			(layer "F.Fab")
			(hide yes)
			(effects
				(font
					(size 1.016 1.016)
					(thickness 0.1524)
				)
			)
		)
		(duplicate_pad_numbers_are_jumpers no)
		(fp_poly
			(pts
				(arc
					(start 5.0673 0)
					(mid -5.0673 0)
					(end 5.0673 0)
				)
			)
			(stroke
				(width 0)
				(type default)
			)
			(fill no)
			(layer "B.CrtYd")
		)
		(fp_poly
			(pts
				(arc
					(start 5.0673 0)
					(mid -5.0673 0)
					(end 5.0673 0)
				)
			)
			(stroke
				(width 0)
				(type default)
			)
			(fill no)
			(layer "F.CrtYd")
		)
		(fp_poly
			(pts
				(arc
					(start 5.0673 0)
					(mid -5.0673 0)
					(end 5.0673 0)
				)
			)
			(stroke
				(width 0)
				(type default)
			)
			(fill no)
			(layer "B.Fab")
		)
		(fp_poly
			(pts
				(arc
					(start 5.0673 0)
					(mid -5.0673 0)
					(end 5.0673 0)
				)
			)
			(stroke
				(width 0)
				(type default)
			)
			(fill no)
			(layer "F.Fab")
		)
		(pad "1" thru_hole circle
			(at 0 0)
			(size 9.525 9.525)
			(drill 3.5052)
			(layers "*.Cu" "*.Mask")
			(remove_unused_layers no)
			(net "Net_11")
			(clearance -2.5019)
			(thermal_gap 0.3048)
			(padstack
				(mode front_inner_back)
				(layer "Inner"
					(shape circle)
					(size 3.9116 3.9116)
					(clearance 0.3048)
				)
				(layer "B.Cu"
					(shape circle)
					(size 9.525 9.525)
					(clearance -2.5019)
				)
			)
		)
	)
	(footprint ""
		(layer "F.Cu")
		(at 83.479386 -136.616186)
		(property "Reference" "C40"
			(at 0 0 0)
			(layer "F.SilkS")
			(hide yes)
			(effects
				(font
					(size 1.27 1.27)
				)
			)
		)
		(property "Value" "SCD1U16V2KX-3GP"
			(at 1.1811 -2.7051 0)
			(unlocked yes)
			(layer "F.Fab")
			(hide yes)
			(effects
				(font
					(size 1.016 1.016)
					(thickness 0.1524)
				)
			)
		)
		(property "Device Type" "C402H22"
			(at 1.1811 -4.2291 0)
			(unlocked yes)
			(layer "F.Fab")
			(hide yes)
			(effects
				(font
					(size 1.016 1.016)
					(thickness 0.1524)
				)
			)
		)
		(duplicate_pad_numbers_are_jumpers no)
		(fp_rect
			(start -0.4318 0.9525)
			(end 0.4318 -0.9525)
			(stroke
				(width 0)
				(type default)
			)
			(fill no)
			(layer "F.CrtYd")
		)
		(fp_rect
			(start -0.4318 0.9525)
			(end 0.4318 -0.9525)
			(stroke
				(width 0)
				(type default)
			)
			(fill no)
			(layer "F.Fab")
		)
		(pad "1" smd custom
			(at 0 -0.4445)
			(size 0.1524 0.1524)
			(layers "F.Cu" "F.Mask" "F.Paste")
			(net "D_FLIP_CLR#")
			(options
				(clearance outline)
				(anchor circle)
			)
			(primitives
				(gr_poly
					(pts
						(arc
							(start 0.3048 -0.2032)
							(mid 0.275042 -0.275042)
							(end 0.2032 -0.3048)
						)
						(arc
							(start -0.2032 -0.3048)
							(mid -0.275042 -0.275042)
							(end -0.3048 -0.2032)
						)
						(arc
							(start -0.3048 0.2032)
							(mid -0.275042 0.275042)
							(end -0.2032 0.3048)
						)
						(arc
							(start 0.2032 0.3048)
							(mid 0.275042 0.275042)
							(end 0.3048 0.2032)
						)
					)
					(width 0)
					(fill yes)
				)
			)
		)
		(pad "2" smd custom
			(at 0 0.4445)
			(size 0.1524 0.1524)
			(layers "F.Cu" "F.Mask" "F.Paste")
			(net "GND")
			(options
				(clearance outline)
				(anchor circle)
			)
			(primitives
				(gr_poly
					(pts
						(arc
							(start 0.3048 -0.2032)
							(mid 0.275042 -0.275042)
							(end 0.2032 -0.3048)
						)
						(arc
							(start -0.2032 -0.3048)
							(mid -0.275042 -0.275042)
							(end -0.3048 -0.2032)
						)
						(arc
							(start -0.3048 0.2032)
							(mid -0.275042 0.275042)
							(end -0.2032 0.3048)
						)
						(arc
							(start 0.2032 0.3048)
							(mid 0.275042 0.275042)
							(end 0.3048 0.2032)
						)
					)
					(width 0)
					(fill yes)
				)
			)
		)
	)
	(footprint ""
		(layer "F.Cu")
		(at 178.40706 -124.60224 180)
		(property "Reference" "R727"
			(at 0 0 180)
			(layer "F.SilkS")
			(hide yes)
			(effects
				(font
					(size 1.27 1.27)
				)
			)
		)
		(property "Value" "0R2J-2-GP"
			(at 0.064008 -3.993896 180)
			(unlocked yes)
			(layer "F.Fab")
			(hide yes)
			(effects
				(font
					(size 1.016 1.016)
					(thickness 0.1524)
				)
			)
		)
		(property "Device Type" "R402H16"
			(at 0.064008 -5.517896 180)
			(unlocked yes)
			(layer "F.Fab")
			(hide yes)
			(effects
				(font
					(size 1.016 1.016)
					(thickness 0.1524)
				)
			)
		)
		(duplicate_pad_numbers_are_jumpers no)
		(fp_line
			(start 0.508 -0.9398)
			(end -0.508 -0.9398)
			(stroke
				(width 0.1524)
				(type default)
			)
			(layer "F.SilkS")
		)
		(fp_line
			(start -0.508 -0.9398)
			(end -0.508 0.9398)
			(stroke
				(width 0.1524)
				(type default)
			)
			(layer "F.SilkS")
		)
		(fp_rect
			(start -0.508 0.9398)
			(end 0.508 -0.9398)
			(stroke
				(width 0)
				(type default)
			)
			(fill no)
			(layer "F.CrtYd")
		)
		(fp_rect
			(start -0.508 0.9398)
			(end 0.508 -0.9398)
			(stroke
				(width 0)
				(type default)
			)
			(fill no)
			(layer "F.Fab")
		)
		(pad "1" smd custom
			(at 0 -0.4445 180)
			(size 0.1397 0.1397)
			(layers "F.Cu" "F.Mask" "F.Paste")
			(net "P1V8_EN")
			(options
				(clearance outline)
				(anchor circle)
			)
			(primitives
				(gr_poly
					(pts
						(arc
							(start -0.1778 -0.2794)
							(mid -0.249642 -0.249642)
							(end -0.2794 -0.1778)
						)
						(arc
							(start -0.2794 0.1778)
							(mid -0.249642 0.249642)
							(end -0.1778 0.2794)
						)
						(arc
							(start 0.1778 0.2794)
							(mid 0.249642 0.249642)
							(end 0.2794 0.1778)
						)
						(arc
							(start 0.2794 -0.1778)
							(mid 0.249642 -0.249642)
							(end 0.1778 -0.2794)
						)
					)
					(width 0)
					(fill yes)
				)
			)
		)
		(pad "2" smd custom
			(at 0 0.4445 180)
			(size 0.1397 0.1397)
			(layers "F.Cu" "F.Mask" "F.Paste")
			(net "P3V3_PG")
			(options
				(clearance outline)
				(anchor circle)
			)
			(primitives
				(gr_poly
					(pts
						(arc
							(start -0.1778 -0.2794)
							(mid -0.249642 -0.249642)
							(end -0.2794 -0.1778)
						)
						(arc
							(start -0.2794 0.1778)
							(mid -0.249642 0.249642)
							(end -0.1778 0.2794)
						)
						(arc
							(start 0.1778 0.2794)
							(mid 0.249642 0.249642)
							(end 0.2794 0.1778)
						)
						(arc
							(start 0.2794 -0.1778)
							(mid 0.249642 -0.249642)
							(end 0.1778 -0.2794)
						)
					)
					(width 0)
					(fill yes)
				)
			)
		)
	)
	(footprint ""
		(layer "F.Cu")
		(at 74.5236 -143.6624 90)
		(property "Reference" "R131"
			(at 0 0 90)
			(layer "F.SilkS")
			(hide yes)
			(effects
				(font
					(size 1.27 1.27)
				)
			)
		)
		(property "Value" "0R2J-2-GP"
			(at 0.064008 -3.993896 90)
			(unlocked yes)
			(layer "F.Fab")
			(hide yes)
			(effects
				(font
					(size 1.016 1.016)
					(thickness 0.1524)
				)
			)
		)
		(property "Device Type" "R402H16"
			(at 0.064008 -5.517896 90)
			(unlocked yes)
			(layer "F.Fab")
			(hide yes)
			(effects
				(font
					(size 1.016 1.016)
					(thickness 0.1524)
				)
			)
		)
		(duplicate_pad_numbers_are_jumpers no)
		(fp_line
			(start 0.508 -0.9398)
			(end -0.508 -0.9398)
			(stroke
				(width 0.1524)
				(type default)
			)
			(layer "F.SilkS")
		)
		(fp_line
			(start -0.508 -0.9398)
			(end -0.508 0.9398)
			(stroke
				(width 0.1524)
				(type default)
			)
			(layer "F.SilkS")
		)
		(fp_rect
			(start -0.508 0.9398)
			(end 0.508 -0.9398)
			(stroke
				(width 0)
				(type default)
			)
			(fill no)
			(layer "F.CrtYd")
		)
		(fp_rect
			(start -0.508 0.9398)
			(end 0.508 -0.9398)
			(stroke
				(width 0)
				(type default)
			)
			(fill no)
			(layer "F.Fab")
		)
		(pad "1" smd custom
			(at 0 -0.4445 90)
			(size 0.1397 0.1397)
			(layers "F.Cu" "F.Mask" "F.Paste")
			(net "I2C_SCC_SCL")
			(options
				(clearance outline)
				(anchor circle)
			)
			(primitives
				(gr_poly
					(pts
						(arc
							(start -0.1778 -0.2794)
							(mid -0.249642 -0.249642)
							(end -0.2794 -0.1778)
						)
						(arc
							(start -0.2794 0.1778)
							(mid -0.249642 0.249642)
							(end -0.1778 0.2794)
						)
						(arc
							(start 0.1778 0.2794)
							(mid 0.249642 0.249642)
							(end 0.2794 0.1778)
						)
						(arc
							(start 0.2794 -0.1778)
							(mid 0.249642 -0.249642)
							(end 0.1778 -0.2794)
						)
					)
					(width 0)
					(fill yes)
				)
			)
		)
		(pad "2" smd custom
			(at 0 0.4445 90)
			(size 0.1397 0.1397)
			(layers "F.Cu" "F.Mask" "F.Paste")
			(net "I2C_SCC_SCL_R")
			(options
				(clearance outline)
				(anchor circle)
			)
			(primitives
				(gr_poly
					(pts
						(arc
							(start -0.1778 -0.2794)
							(mid -0.249642 -0.249642)
							(end -0.2794 -0.1778)
						)
						(arc
							(start -0.2794 0.1778)
							(mid -0.249642 0.249642)
							(end -0.1778 0.2794)
						)
						(arc
							(start 0.1778 0.2794)
							(mid 0.249642 0.249642)
							(end 0.2794 0.1778)
						)
						(arc
							(start 0.2794 -0.1778)
							(mid 0.249642 -0.249642)
							(end 0.1778 -0.2794)
						)
					)
					(width 0)
					(fill yes)
				)
			)
		)
	)
	(footprint ""
		(layer "F.Cu")
		(at 23.2918 -183.5658 90)
		(property "Reference" "L8"
			(at 0 0 90)
			(layer "F.SilkS")
			(hide yes)
			(effects
				(font
					(size 1.27 1.27)
				)
			)
		)
		(property "Value" "BLM21PG220SN1DGP"
			(at 0.0254 -5.6896 90)
			(unlocked yes)
			(layer "F.Fab")
			(hide yes)
			(effects
				(font
					(size 1.016 1.016)
					(thickness 0.1524)
				)
			)
		)
		(property "Device Type" "L20125H42"
			(at 0.0254 -7.5946 90)
			(unlocked yes)
			(layer "F.Fab")
			(hide yes)
			(effects
				(font
					(size 1.016 1.016)
					(thickness 0.1524)
				)
			)
		)
		(duplicate_pad_numbers_are_jumpers no)
		(fp_line
			(start 0.9144 -1.7018)
			(end -0.9144 -1.7018)
			(stroke
				(width 0.1524)
				(type default)
			)
			(layer "F.SilkS")
		)
		(fp_line
			(start -0.9144 -1.7018)
			(end -0.9144 1.7018)
			(stroke
				(width 0.1524)
				(type default)
			)
			(layer "F.SilkS")
		)
		(fp_line
			(start 0.9144 1.7018)
			(end 0.9144 -1.7018)
			(stroke
				(width 0.1524)
				(type default)
			)
			(layer "F.SilkS")
		)
		(fp_line
			(start -0.9144 1.7018)
			(end 0.9144 1.7018)
			(stroke
				(width 0.1524)
				(type default)
			)
			(layer "F.SilkS")
		)
		(fp_rect
			(start -1.0033 1.778)
			(end 1.0033 -1.778)
			(stroke
				(width 0)
				(type default)
			)
			(fill no)
			(layer "F.CrtYd")
		)
		(fp_poly
			(pts
				(xy -1.0033 -1.778) (xy 1.0033 -1.778) (xy 1.0033 1.778) (xy -1.0033 1.778)
			)
			(stroke
				(width 0)
				(type default)
			)
			(fill no)
			(layer "F.Fab")
		)
		(pad "1" smd rect
			(at 0 -0.9652 90)
			(size 1.397 1.143)
			(layers "F.Cu" "F.Mask" "F.Paste")
			(net "P12V_STBY")
		)
		(pad "2" smd rect
			(at 0 0.9652 90)
			(size 1.397 1.143)
			(layers "F.Cu" "F.Mask" "F.Paste")
			(net "P12V_STBY_VIN_PU2")
		)
	)
)
